(kicad_pcb
	(version 20260206)
	(generator "pcbnew")
	(generator_version "10.0")
	(general
		(thickness 1.6)
		(legacy_teardrops no)
	)
	(paper "A4")
	(title_block
		(title "panther-plus-userver — 13130-1b_20150205.brd")
		(comment 1 "Honey Badger (Wiwynn) / footprints 66-73 of 1509")
	)
	(layers
		(0 "F.Cu" signal "TOP")
		(4 "In1.Cu" signal "L2")
		(6 "In2.Cu" signal "L3")
		(8 "In3.Cu" signal "L4")
		(10 "In4.Cu" signal "L5")
		(12 "In5.Cu" signal "L6")
		(14 "In6.Cu" signal "L7")
		(16 "In7.Cu" signal "L8")
		(18 "In8.Cu" signal "L9")
		(20 "In9.Cu" signal "L10")
		(22 "In10.Cu" signal "L11")
		(2 "B.Cu" signal "BOTTOM")
		(9 "F.Adhes" user "F.Adhesive")
		(11 "B.Adhes" user "B.Adhesive")
		(13 "F.Paste" user "Package Geometry/Pastemask Top")
		(15 "B.Paste" user "Package Geometry/Pastemask Bottom")
		(5 "F.SilkS" user "Ref Des/Silkscreen Top")
		(7 "B.SilkS" user "Ref Des/Silkscreen Bottom")
		(1 "F.Mask" user "Board Geometry/Soldermask Top")
		(3 "B.Mask" user "Board Geometry/Soldermask Bottom")
		(17 "Dwgs.User" user "User.Drawings")
		(19 "Cmts.User" user "User.Comments")
		(21 "Eco1.User" user "User.Eco1")
		(23 "Eco2.User" user "User.Eco2")
		(25 "Edge.Cuts" user "Board Geometry/Outline")
		(27 "Margin" user)
		(31 "F.CrtYd" user "Package Geometry/Place Bound Top")
		(29 "B.CrtYd" user "Package Geometry/Place Bound Bottom")
		(35 "F.Fab" user "Ref Des/Assembly Top")
		(33 "B.Fab" user "Ref Des/Assembly Bottom")
	)
	(footprint ""
		(layer "F.Cu")
		(at 46.1772 -51.3334)
		(property "Reference" "C52"
			(at 0 0 0)
			(layer "F.SilkS")
			(hide yes)
			(effects
				(font
					(size 1.27 1.27)
				)
			)
		)
		(property "Value" "SCD1U10V2KX-5GP"
			(at 1.8923 -1.2065 0)
			(unlocked yes)
			(layer "F.Fab")
			(hide yes)
			(effects
				(font
					(size 1.016 1.016)
					(thickness 0.1524)
				)
			)
		)
		(property "Device Type" "C402H22"
			(at 1.8923 -2.7305 0)
			(unlocked yes)
			(layer "F.Fab")
			(hide yes)
			(effects
				(font
					(size 1.016 1.016)
					(thickness 0.1524)
				)
			)
		)
		(duplicate_pad_numbers_are_jumpers no)
		(fp_rect
			(start -0.381 0.7366)
			(end 0.381 -0.7366)
			(stroke
				(width 0)
				(type default)
			)
			(fill no)
			(layer "F.CrtYd")
		)
		(fp_rect
			(start -0.381 0.7366)
			(end 0.381 -0.7366)
			(stroke
				(width 0)
				(type default)
			)
			(fill no)
			(layer "F.Fab")
		)
		(pad "1" smd custom
			(at 0 -0.4572)
			(size 0.1143 0.1143)
			(layers "F.Cu" "F.Mask" "F.Paste")
			(net "P3V3_CLK_VDD25")
			(options
				(clearance outline)
				(anchor circle)
			)
			(primitives
				(gr_poly
					(pts
						(arc
							(start -0.254 -0.1778)
							(mid -0.239121 -0.213721)
							(end -0.2032 -0.2286)
						)
						(arc
							(start 0.2032 -0.2286)
							(mid 0.239121 -0.213721)
							(end 0.254 -0.1778)
						)
						(arc
							(start 0.254 0.1778)
							(mid 0.239121 0.213721)
							(end 0.2032 0.2286)
						)
						(arc
							(start -0.2032 0.2286)
							(mid -0.239121 0.213721)
							(end -0.254 0.1778)
						)
					)
					(width 0)
					(fill yes)
				)
			)
		)
		(pad "2" smd custom
			(at 0 0.4572)
			(size 0.1143 0.1143)
			(layers "F.Cu" "F.Mask" "F.Paste")
			(net "GND")
			(options
				(clearance outline)
				(anchor circle)
			)
			(primitives
				(gr_poly
					(pts
						(arc
							(start -0.254 -0.1778)
							(mid -0.239121 -0.213721)
							(end -0.2032 -0.2286)
						)
						(arc
							(start 0.2032 -0.2286)
							(mid 0.239121 -0.213721)
							(end 0.254 -0.1778)
						)
						(arc
							(start 0.254 0.1778)
							(mid 0.239121 0.213721)
							(end 0.2032 0.2286)
						)
						(arc
							(start -0.2032 0.2286)
							(mid -0.239121 0.213721)
							(end -0.254 0.1778)
						)
					)
					(width 0)
					(fill yes)
				)
			)
		)
	)
	(footprint ""
		(layer "F.Cu")
		(at 184.16524 -50.82159 -90)
		(property "Reference" "U23"
			(at 0 0 270)
			(layer "F.SilkS")
			(hide yes)
			(effects
				(font
					(size 1.27 1.27)
				)
			)
		)
		(property "Value" "LMV321IDCKR-1-GP"
			(at -2.3368 -8.6868 270)
			(unlocked yes)
			(layer "F.Fab")
			(hide yes)
			(effects
				(font
					(size 1.016 1.016)
					(thickness 0.1524)
				)
			)
		)
		(property "Device Type" "SC70-5H44"
			(at -2.3114 -10.414 270)
			(unlocked yes)
			(layer "F.Fab")
			(hide yes)
			(effects
				(font
					(size 1.016 1.016)
					(thickness 0.1524)
				)
			)
		)
		(duplicate_pad_numbers_are_jumpers no)
		(fp_line
			(start -1.0033 0.3302)
			(end -1.0033 -0.3302)
			(stroke
				(width 0.1524)
				(type default)
			)
			(layer "F.SilkS")
		)
		(fp_line
			(start 1.0033 0.3302)
			(end -1.0033 0.3302)
			(stroke
				(width 0.1524)
				(type default)
			)
			(layer "F.SilkS")
		)
		(fp_line
			(start -1.0033 -0.3302)
			(end 1.0033 -0.3302)
			(stroke
				(width 0.1524)
				(type default)
			)
			(layer "F.SilkS")
		)
		(fp_line
			(start 1.0033 -0.3302)
			(end 1.0033 0.3302)
			(stroke
				(width 0.1524)
				(type default)
			)
			(layer "F.SilkS")
		)
		(fp_poly
			(pts
				(xy -1.0033 1.4859) (xy -1.0033 0.8001) (xy -1.1811 0.8001) (xy -1.1811 -0.8001) (xy -1.0033 -0.8001)
				(xy -1.0033 -1.4859) (xy 1.0033 -1.4859) (xy 1.0033 -0.8001) (xy 1.1811 -0.8001) (xy 1.1811 0.8001)
				(xy 1.0033 0.8001) (xy 1.0033 1.4859) (xy 0.2921 1.4859) (xy 0.2921 0.8001) (xy -0.2921 0.8001)
				(xy -0.2921 1.4859)
			)
			(stroke
				(width 0)
				(type default)
			)
			(fill no)
			(layer "F.CrtYd")
		)
		(fp_poly
			(pts
				(xy -1.0033 1.4859) (xy -1.0033 0.8001) (xy -1.1811 0.8001) (xy -1.1811 -0.8001) (xy -1.0033 -0.8001)
				(xy -1.0033 -1.4859) (xy 1.0033 -1.4859) (xy 1.0033 -0.8001) (xy 1.1811 -0.8001) (xy 1.1811 0.8001)
				(xy 1.0033 0.8001) (xy 1.0033 1.4859) (xy 0.2921 1.4859) (xy 0.2921 0.8001) (xy -0.2921 0.8001)
				(xy -0.2921 1.4859)
			)
			(stroke
				(width 0)
				(type default)
			)
			(fill no)
			(layer "F.Fab")
		)
		(pad "1" smd rect
			(at 0.65024 -0.93472 270)
			(size 0.3556 0.762)
			(layers "F.Cu" "F.Mask" "F.Paste")
			(net "PV_VDDR_VREF_RW")
		)
		(pad "2" smd rect
			(at 0 -0.93472 270)
			(size 0.3556 0.762)
			(layers "F.Cu" "F.Mask" "F.Paste")
			(net "GND")
		)
		(pad "3" smd rect
			(at -0.65024 -0.93472 270)
			(size 0.3556 0.762)
			(layers "F.Cu" "F.Mask" "F.Paste")
			(net "PV_VDDR_VREF_A_FB")
		)
		(pad "4" smd rect
			(at -0.65024 0.93472 270)
			(size 0.3556 0.762)
			(layers "F.Cu" "F.Mask" "F.Paste")
			(net "PV_VDDR_VREF_A_FB")
		)
		(pad "5" smd rect
			(at 0.65024 0.93472 270)
			(size 0.3556 0.762)
			(layers "F.Cu" "F.Mask" "F.Paste")
			(net "P3V3_STBY")
		)
	)
	(footprint ""
		(layer "F.Cu")
		(at 146.558 -20.701)
		(property "Reference" "R100"
			(at 0 0 0)
			(layer "F.SilkS")
			(hide yes)
			(effects
				(font
					(size 1.27 1.27)
				)
			)
		)
		(property "Value" "0R2J-2-GP"
			(at 0.064008 -3.993896 0)
			(unlocked yes)
			(layer "F.Fab")
			(hide yes)
			(effects
				(font
					(size 1.016 1.016)
					(thickness 0.1524)
				)
			)
		)
		(property "Device Type" "R402H16"
			(at 0.064008 -5.517896 0)
			(unlocked yes)
			(layer "F.Fab")
			(hide yes)
			(effects
				(font
					(size 1.016 1.016)
					(thickness 0.1524)
				)
			)
		)
		(duplicate_pad_numbers_are_jumpers no)
		(fp_rect
			(start -0.381 0.8382)
			(end 0.381 -0.8382)
			(stroke
				(width 0)
				(type default)
			)
			(fill no)
			(layer "F.CrtYd")
		)
		(fp_rect
			(start -0.381 0.8382)
			(end 0.381 -0.8382)
			(stroke
				(width 0)
				(type default)
			)
			(fill no)
			(layer "F.Fab")
		)
		(pad "1" smd custom
			(at 0 -0.4318)
			(size 0.127 0.127)
			(layers "F.Cu" "F.Mask" "F.Paste")
			(net "P3V3_STBY")
			(options
				(clearance outline)
				(anchor circle)
			)
			(primitives
				(gr_poly
					(pts
						(arc
							(start -0.2032 -0.2794)
							(mid -0.239121 -0.264521)
							(end -0.254 -0.2286)
						)
						(arc
							(start -0.254 0.2286)
							(mid -0.239121 0.264521)
							(end -0.2032 0.2794)
						)
						(arc
							(start 0.2032 0.2794)
							(mid 0.239121 0.264521)
							(end 0.254 0.2286)
						)
						(arc
							(start 0.254 -0.2286)
							(mid 0.239121 -0.264521)
							(end 0.2032 -0.2794)
						)
					)
					(width 0)
					(fill yes)
				)
			)
		)
		(pad "2" smd custom
			(at 0 0.4318)
			(size 0.127 0.127)
			(layers "F.Cu" "F.Mask" "F.Paste")
			(net "MSEL1")
			(options
				(clearance outline)
				(anchor circle)
			)
			(primitives
				(gr_poly
					(pts
						(arc
							(start -0.2032 -0.2794)
							(mid -0.239121 -0.264521)
							(end -0.254 -0.2286)
						)
						(arc
							(start -0.254 0.2286)
							(mid -0.239121 0.264521)
							(end -0.2032 0.2794)
						)
						(arc
							(start 0.2032 0.2794)
							(mid 0.239121 0.264521)
							(end 0.254 0.2286)
						)
						(arc
							(start 0.254 -0.2286)
							(mid 0.239121 -0.264521)
							(end 0.2032 -0.2794)
						)
					)
					(width 0)
					(fill yes)
				)
			)
		)
	)
	(footprint ""
		(layer "F.Cu")
		(at 23.6728 -37.465)
		(property "Reference" "PC80"
			(at 0 0 0)
			(layer "F.SilkS")
			(hide yes)
			(effects
				(font
					(size 1.27 1.27)
				)
			)
		)
		(property "Value" "SC100U6D3V6MX-GP"
			(at 0.0127 -3.4671 0)
			(unlocked yes)
			(layer "F.Fab")
			(hide yes)
			(effects
				(font
					(size 1.016 1.016)
					(thickness 0.1524)
				)
			)
		)
		(property "Device Type" "C1206H71"
			(at 0.0127 -4.9911 0)
			(unlocked yes)
			(layer "F.Fab")
			(hide yes)
			(effects
				(font
					(size 1.016 1.016)
					(thickness 0.1524)
				)
			)
		)
		(duplicate_pad_numbers_are_jumpers no)
		(fp_rect
			(start -1.0541 1.9812)
			(end 1.0541 -1.9812)
			(stroke
				(width 0)
				(type default)
			)
			(fill no)
			(layer "F.CrtYd")
		)
		(fp_rect
			(start -1.0541 1.9812)
			(end 1.0541 -1.9812)
			(stroke
				(width 0)
				(type default)
			)
			(fill no)
			(layer "F.Fab")
		)
		(pad "1" smd rect
			(at 0 -1.3462)
			(size 1.8542 1.016)
			(layers "F.Cu" "F.Mask" "F.Paste")
			(net "P3V3_STBY_OUT")
		)
		(pad "2" smd rect
			(at 0 1.3462)
			(size 1.8542 1.016)
			(layers "F.Cu" "F.Mask" "F.Paste")
			(net "GND")
		)
	)
	(footprint ""
		(layer "F.Cu")
		(at 190.881 -39.878)
		(property "Reference" "PR124"
			(at 0 0 0)
			(layer "F.SilkS")
			(hide yes)
			(effects
				(font
					(size 1.27 1.27)
				)
			)
		)
		(property "Value" "0R2J-2-GP"
			(at 1.7907 -1.1176 0)
			(unlocked yes)
			(layer "F.Fab")
			(hide yes)
			(effects
				(font
					(size 1.016 1.016)
					(thickness 0.1524)
				)
			)
		)
		(property "Device Type" "R402H16"
			(at 1.7907 -2.6416 0)
			(unlocked yes)
			(layer "F.Fab")
			(hide yes)
			(effects
				(font
					(size 1.016 1.016)
					(thickness 0.1524)
				)
			)
		)
		(duplicate_pad_numbers_are_jumpers no)
		(fp_rect
			(start -0.381 0.8382)
			(end 0.381 -0.8382)
			(stroke
				(width 0)
				(type default)
			)
			(fill no)
			(layer "F.CrtYd")
		)
		(fp_rect
			(start -0.381 0.8382)
			(end 0.381 -0.8382)
			(stroke
				(width 0)
				(type default)
			)
			(fill no)
			(layer "F.Fab")
		)
		(pad "1" smd custom
			(at 0 -0.4318)
			(size 0.127 0.127)
			(layers "F.Cu" "F.Mask" "F.Paste")
			(net "GND")
			(options
				(clearance outline)
				(anchor circle)
			)
			(primitives
				(gr_poly
					(pts
						(arc
							(start -0.2032 -0.2794)
							(mid -0.239121 -0.264521)
							(end -0.254 -0.2286)
						)
						(arc
							(start -0.254 0.2286)
							(mid -0.239121 0.264521)
							(end -0.2032 0.2794)
						)
						(arc
							(start 0.2032 0.2794)
							(mid 0.239121 0.264521)
							(end 0.254 0.2286)
						)
						(arc
							(start 0.254 -0.2286)
							(mid 0.239121 -0.264521)
							(end 0.2032 -0.2794)
						)
					)
					(width 0)
					(fill yes)
				)
			)
		)
		(pad "2" smd custom
			(at 0 0.4318)
			(size 0.127 0.127)
			(layers "F.Cu" "F.Mask" "F.Paste")
			(net "VR_PVDDR_A_PSI")
			(options
				(clearance outline)
				(anchor circle)
			)
			(primitives
				(gr_poly
					(pts
						(arc
							(start -0.2032 -0.2794)
							(mid -0.239121 -0.264521)
							(end -0.254 -0.2286)
						)
						(arc
							(start -0.254 0.2286)
							(mid -0.239121 0.264521)
							(end -0.2032 0.2794)
						)
						(arc
							(start 0.2032 0.2794)
							(mid 0.239121 0.264521)
							(end 0.254 0.2286)
						)
						(arc
							(start 0.254 -0.2286)
							(mid 0.239121 -0.264521)
							(end 0.2032 -0.2794)
						)
					)
					(width 0)
					(fill yes)
				)
			)
		)
	)
	(footprint ""
		(layer "F.Cu")
		(at 59.944 -63.754 180)
		(property "Reference" "PC39"
			(at 0 0 180)
			(layer "F.SilkS")
			(hide yes)
			(effects
				(font
					(size 1.27 1.27)
				)
			)
		)
		(property "Value" "SC47U6D3V5MX-1-GP"
			(at -0.0762 -6.1214 180)
			(unlocked yes)
			(layer "F.Fab")
			(hide yes)
			(effects
				(font
					(size 1.016 1.016)
					(thickness 0.1524)
				)
			)
		)
		(property "Device Type" "C805H54"
			(at -0.0762 -8.1534 180)
			(unlocked yes)
			(layer "F.Fab")
			(hide yes)
			(effects
				(font
					(size 1.016 1.016)
					(thickness 0.1524)
				)
			)
		)
		(duplicate_pad_numbers_are_jumpers no)
		(fp_line
			(start 0.6096 0)
			(end -0.6096 0)
			(stroke
				(width 0.3048)
				(type default)
			)
			(layer "F.SilkS")
		)
		(fp_poly
			(pts
				(xy -0.9017 1.4351) (xy 0.9017 1.4351) (xy 0.9017 -1.4351) (xy -0.9017 -1.4351)
			)
			(stroke
				(width 0)
				(type default)
			)
			(fill no)
			(layer "F.CrtYd")
		)
		(fp_poly
			(pts
				(xy 0.9017 1.4351) (xy 0.9017 -1.4351) (xy -0.9017 -1.4351) (xy -0.9017 1.4351)
			)
			(stroke
				(width 0)
				(type default)
			)
			(fill no)
			(layer "F.Fab")
		)
		(pad "1" smd rect
			(at 0 -0.8382 180)
			(size 1.5494 0.9398)
			(layers "F.Cu" "F.Mask" "F.Paste")
			(net "PVCCP")
		)
		(pad "2" smd rect
			(at 0 0.8382 180)
			(size 1.5494 0.9398)
			(layers "F.Cu" "F.Mask" "F.Paste")
			(net "GND")
		)
	)
	(footprint ""
		(layer "F.Cu")
		(at 20.828 -49.276 90)
		(property "Reference" "PR46"
			(at 0 0 90)
			(layer "F.SilkS")
			(hide yes)
			(effects
				(font
					(size 1.27 1.27)
				)
			)
		)
		(property "Value" "10KR2F-2-GP"
			(at 1.7907 -1.1176 90)
			(unlocked yes)
			(layer "F.Fab")
			(hide yes)
			(effects
				(font
					(size 1.016 1.016)
					(thickness 0.1524)
				)
			)
		)
		(property "Device Type" "R402H16"
			(at 1.7907 -2.6416 90)
			(unlocked yes)
			(layer "F.Fab")
			(hide yes)
			(effects
				(font
					(size 1.016 1.016)
					(thickness 0.1524)
				)
			)
		)
		(duplicate_pad_numbers_are_jumpers no)
		(fp_rect
			(start -0.381 0.8382)
			(end 0.381 -0.8382)
			(stroke
				(width 0)
				(type default)
			)
			(fill no)
			(layer "F.CrtYd")
		)
		(fp_rect
			(start -0.381 0.8382)
			(end 0.381 -0.8382)
			(stroke
				(width 0)
				(type default)
			)
			(fill no)
			(layer "F.Fab")
		)
		(pad "1" smd custom
			(at 0 -0.4318 90)
			(size 0.127 0.127)
			(layers "F.Cu" "F.Mask" "F.Paste")
			(net "VR_PVCCP_ISUMP_R2")
			(options
				(clearance outline)
				(anchor circle)
			)
			(primitives
				(gr_poly
					(pts
						(arc
							(start -0.2032 -0.2794)
							(mid -0.239121 -0.264521)
							(end -0.254 -0.2286)
						)
						(arc
							(start -0.254 0.2286)
							(mid -0.239121 0.264521)
							(end -0.2032 0.2794)
						)
						(arc
							(start 0.2032 0.2794)
							(mid 0.239121 0.264521)
							(end 0.254 0.2286)
						)
						(arc
							(start 0.254 -0.2286)
							(mid 0.239121 -0.264521)
							(end 0.2032 -0.2794)
						)
					)
					(width 0)
					(fill yes)
				)
			)
		)
		(pad "2" smd custom
			(at 0 0.4318 90)
			(size 0.127 0.127)
			(layers "F.Cu" "F.Mask" "F.Paste")
			(net "VR_PVCCP_ISEN1")
			(options
				(clearance outline)
				(anchor circle)
			)
			(primitives
				(gr_poly
					(pts
						(arc
							(start -0.2032 -0.2794)
							(mid -0.239121 -0.264521)
							(end -0.254 -0.2286)
						)
						(arc
							(start -0.254 0.2286)
							(mid -0.239121 0.264521)
							(end -0.2032 0.2794)
						)
						(arc
							(start 0.2032 0.2794)
							(mid 0.239121 0.264521)
							(end 0.254 0.2286)
						)
						(arc
							(start 0.254 -0.2286)
							(mid 0.239121 -0.264521)
							(end 0.2032 -0.2794)
						)
					)
					(width 0)
					(fill yes)
				)
			)
		)
	)
	(footprint ""
		(layer "F.Cu")
		(at 43.0022 -49.9364 -90)
		(property "Reference" "R42"
			(at 0 0 270)
			(layer "F.SilkS")
			(hide yes)
			(effects
				(font
					(size 1.27 1.27)
				)
			)
		)
		(property "Value" "1KR2F-3-GP"
			(at 0.064008 -3.993896 270)
			(unlocked yes)
			(layer "F.Fab")
			(hide yes)
			(effects
				(font
					(size 1.016 1.016)
					(thickness 0.1524)
				)
			)
		)
		(property "Device Type" "R402H16"
			(at 0.064008 -5.517896 270)
			(unlocked yes)
			(layer "F.Fab")
			(hide yes)
			(effects
				(font
					(size 1.016 1.016)
					(thickness 0.1524)
				)
			)
		)
		(duplicate_pad_numbers_are_jumpers no)
		(fp_rect
			(start -0.381 0.8382)
			(end 0.381 -0.8382)
			(stroke
				(width 0)
				(type default)
			)
			(fill no)
			(layer "F.CrtYd")
		)
		(fp_rect
			(start -0.381 0.8382)
			(end 0.381 -0.8382)
			(stroke
				(width 0)
				(type default)
			)
			(fill no)
			(layer "F.Fab")
		)
		(pad "1" smd custom
			(at 0 -0.4318 270)
			(size 0.127 0.127)
			(layers "F.Cu" "F.Mask" "F.Paste")
			(net "P3V3_CPU")
			(options
				(clearance outline)
				(anchor circle)
			)
			(primitives
				(gr_poly
					(pts
						(arc
							(start -0.2032 -0.2794)
							(mid -0.239121 -0.264521)
							(end -0.254 -0.2286)
						)
						(arc
							(start -0.254 0.2286)
							(mid -0.239121 0.264521)
							(end -0.2032 0.2794)
						)
						(arc
							(start 0.2032 0.2794)
							(mid 0.239121 0.264521)
							(end 0.254 0.2286)
						)
						(arc
							(start 0.254 -0.2286)
							(mid 0.239121 -0.264521)
							(end 0.2032 -0.2794)
						)
					)
					(width 0)
					(fill yes)
				)
			)
		)
		(pad "2" smd custom
			(at 0 0.4318 270)
			(size 0.127 0.127)
			(layers "F.Cu" "F.Mask" "F.Paste")
			(net "GND")
			(options
				(clearance outline)
				(anchor circle)
			)
			(primitives
				(gr_poly
					(pts
						(arc
							(start -0.2032 -0.2794)
							(mid -0.239121 -0.264521)
							(end -0.254 -0.2286)
						)
						(arc
							(start -0.254 0.2286)
							(mid -0.239121 0.264521)
							(end -0.2032 0.2794)
						)
						(arc
							(start 0.2032 0.2794)
							(mid 0.239121 0.264521)
							(end 0.254 0.2286)
						)
						(arc
							(start 0.254 -0.2286)
							(mid 0.239121 -0.264521)
							(end 0.2032 -0.2794)
						)
					)
					(width 0)
					(fill yes)
				)
			)
		)
	)
)
